(kicad_pcb
	(version 20260206)
	(generator "pcbnew")
	(generator_version "10.0")
	(general
		(thickness 1.6)
		(legacy_teardrops no)
	)
	(paper "A4")
	(title_block
		(title "Wiwynn_Tioga_Pass_MB.brd")
		(comment 1 "Tioga Pass / footprints 1621-1626 of 4770")
	)
	(layers
		(0 "F.Cu" signal "TOP")
		(4 "In1.Cu" signal "L2GND")
		(6 "In2.Cu" signal "L3")
		(8 "In3.Cu" signal "L4GND")
		(10 "In4.Cu" signal "L5")
		(12 "In5.Cu" signal "L6GND")
		(14 "In6.Cu" signal "L7VCC")
		(16 "In7.Cu" signal "L8VCC")
		(18 "In8.Cu" signal "L9GND")
		(20 "In9.Cu" signal "L10")
		(22 "In10.Cu" signal "L11GND")
		(24 "In11.Cu" signal "L12")
		(26 "In12.Cu" signal "L13GND")
		(2 "B.Cu" signal "BOTTOM")
		(9 "F.Adhes" user "F.Adhesive")
		(11 "B.Adhes" user "B.Adhesive")
		(13 "F.Paste" user "Package Geometry/Pastemask Top")
		(15 "B.Paste" user "Package Geometry/Pastemask Bottom")
		(5 "F.SilkS" user "Ref Des/Silkscreen Top")
		(7 "B.SilkS" user "Ref Des/Silkscreen Bottom")
		(1 "F.Mask" user "Board Geometry/Soldermask Top")
		(3 "B.Mask" user "Board Geometry/Soldermask Bottom")
		(17 "Dwgs.User" user "User.Drawings")
		(19 "Cmts.User" user "User.Comments")
		(21 "Eco1.User" user "User.Eco1")
		(23 "Eco2.User" user "User.Eco2")
		(25 "Edge.Cuts" user "Board Geometry/Outline")
		(27 "Margin" user)
		(31 "F.CrtYd" user "Package Geometry/Place Bound Top")
		(29 "B.CrtYd" user "Package Geometry/Place Bound Bottom")
		(35 "F.Fab" user "Ref Des/Assembly Top")
		(33 "B.Fab" user "Ref Des/Assembly Bottom")
	)
	(footprint ""
		(layer "F.Cu")
		(at 15.072106 -110.707424 -90)
		(property "Reference" "J1B4"
			(at 0 0 270)
			(layer "F.SilkS")
			(hide yes)
			(effects
				(font
					(size 1.27 1.27)
				)
			)
		)
		(property "Value" "*"
			(at 2.6924 -3.0734 270)
			(unlocked yes)
			(layer "F.Fab")
			(hide yes)
			(effects
				(font
					(size 1.27 1.016)
					(thickness 0.1524)
				)
			)
		)
		(property "Device Type" "CLX-CONN3A-1-GP_CONN-G3-CLX-COA"
			(at 2.6924 -4.5974 270)
			(unlocked yes)
			(layer "F.Fab")
			(hide yes)
			(effects
				(font
					(size 1.27 1.016)
					(thickness 0.1524)
				)
			)
		)
		(duplicate_pad_numbers_are_jumpers no)
		(fp_line
			(start -2.6543 3.1369)
			(end -1.3335 3.1369)
			(stroke
				(width 0.3302)
				(type default)
			)
			(layer "F.SilkS")
		)
		(fp_line
			(start -2.7432 3.048)
			(end -2.7432 1.2573)
			(stroke
				(width 0.1524)
				(type default)
			)
			(layer "F.SilkS")
		)
		(fp_line
			(start -1.2446 3.048)
			(end -2.7432 3.048)
			(stroke
				(width 0.1524)
				(type default)
			)
			(layer "F.SilkS")
		)
		(fp_line
			(start 1.2446 3.048)
			(end 1.2446 1.2573)
			(stroke
				(width 0.1524)
				(type default)
			)
			(layer "F.SilkS")
		)
		(fp_line
			(start 2.7432 3.048)
			(end 1.2446 3.048)
			(stroke
				(width 0.1524)
				(type default)
			)
			(layer "F.SilkS")
		)
		(fp_line
			(start -3.2512 1.2573)
			(end -3.2512 -1.2573)
			(stroke
				(width 0.1524)
				(type default)
			)
			(layer "F.SilkS")
		)
		(fp_line
			(start -2.7432 1.2573)
			(end -3.2512 1.2573)
			(stroke
				(width 0.1524)
				(type default)
			)
			(layer "F.SilkS")
		)
		(fp_line
			(start -1.2446 1.2573)
			(end -1.2446 3.048)
			(stroke
				(width 0.1524)
				(type default)
			)
			(layer "F.SilkS")
		)
		(fp_line
			(start 1.2446 1.2573)
			(end -1.2446 1.2573)
			(stroke
				(width 0.1524)
				(type default)
			)
			(layer "F.SilkS")
		)
		(fp_line
			(start 2.7432 1.2573)
			(end 2.7432 3.048)
			(stroke
				(width 0.1524)
				(type default)
			)
			(layer "F.SilkS")
		)
		(fp_line
			(start 3.2512 1.2573)
			(end 2.7432 1.2573)
			(stroke
				(width 0.1524)
				(type default)
			)
			(layer "F.SilkS")
		)
		(fp_line
			(start -3.2512 -1.2573)
			(end -0.7493 -1.2573)
			(stroke
				(width 0.1524)
				(type default)
			)
			(layer "F.SilkS")
		)
		(fp_line
			(start -0.7493 -1.2573)
			(end -0.7493 -3.048)
			(stroke
				(width 0.1524)
				(type default)
			)
			(layer "F.SilkS")
		)
		(fp_line
			(start 0.7493 -1.2573)
			(end 3.2512 -1.2573)
			(stroke
				(width 0.1524)
				(type default)
			)
			(layer "F.SilkS")
		)
		(fp_line
			(start 3.2512 -1.2573)
			(end 3.2512 1.2573)
			(stroke
				(width 0.1524)
				(type default)
			)
			(layer "F.SilkS")
		)
		(fp_line
			(start -0.7493 -3.048)
			(end 0.7493 -3.048)
			(stroke
				(width 0.1524)
				(type default)
			)
			(layer "F.SilkS")
		)
		(fp_line
			(start 0.7493 -3.048)
			(end 0.7493 -1.2573)
			(stroke
				(width 0.1524)
				(type default)
			)
			(layer "F.SilkS")
		)
		(fp_poly
			(pts
				(xy -2.014474 3.124708) (xy -2.649474 3.759708) (xy -1.379474 3.759708)
			)
			(stroke
				(width 0)
				(type default)
			)
			(fill yes)
			(layer "F.SilkS")
		)
		(fp_poly
			(pts
				(xy -0.254 -2.2987) (xy 0.254 -2.2987) (xy 0.254 -1.0033) (xy 2.9972 -1.0033) (xy 2.9972 1.0033)
				(xy 2.2479 1.0033) (xy 2.2479 2.2987) (xy 1.7399 2.2987) (xy 1.7399 1.0033) (xy -1.7399 1.0033)
				(xy -1.7399 2.2987) (xy -2.2479 2.2987) (xy -2.2479 1.0033) (xy -2.9972 1.0033) (xy -2.9972 -1.0033)
				(xy -0.254 -1.0033)
			)
			(stroke
				(width 0)
				(type default)
			)
			(fill no)
			(layer "F.CrtYd")
		)
		(fp_poly
			(pts
				(xy -2.9972 3.302) (xy -2.9972 1.5113) (xy -3.5052 1.5113) (xy -3.5052 -1.5113) (xy -1.0033 -1.5113)
				(xy -1.0033 -3.302) (xy 1.0033 -3.302) (xy 1.0033 -1.5113) (xy 3.5052 -1.5113) (xy 3.5052 -0.00635)
				(xy 2.9972 -0.00635) (xy 2.9972 -1.0033) (xy 0.254 -1.0033) (xy 0.254 -2.2987) (xy -0.254 -2.2987)
				(xy -0.254 -1.0033) (xy -2.9972 -1.0033) (xy -2.9972 1.0033) (xy -2.2479 1.0033) (xy -2.2479 2.2987)
				(xy -1.7399 2.2987) (xy -1.7399 1.0033) (xy 1.7399 1.0033) (xy 1.7399 2.2987) (xy 2.2479 2.2987)
				(xy 2.2479 1.0033) (xy 2.9972 1.0033) (xy 2.9972 0.00635) (xy 3.5052 0.00635) (xy 3.5052 1.5113)
				(xy 2.9972 1.5113) (xy 2.9972 3.302) (xy 0.9906 3.302) (xy 0.9906 1.5113) (xy -0.9906 1.5113) (xy -0.9906 3.302)
			)
			(stroke
				(width 0)
				(type default)
			)
			(fill no)
			(layer "F.CrtYd")
		)
		(fp_poly
			(pts
				(xy -2.9972 3.302) (xy -2.9972 1.5113) (xy -3.5052 1.5113) (xy -3.5052 -1.5113) (xy -1.0033 -1.5113)
				(xy -1.0033 -3.302) (xy 1.0033 -3.302) (xy 1.0033 -1.5113) (xy 3.5052 -1.5113) (xy 3.5052 1.5113)
				(xy 2.9972 1.5113) (xy 2.9972 3.302) (xy 0.9906 3.302) (xy 0.9906 1.5113) (xy -0.9906 1.5113) (xy -0.9906 3.302)
			)
			(stroke
				(width 0)
				(type default)
			)
			(fill no)
			(layer "F.Fab")
		)
		(pad "1" smd rect
			(at -1.999996 1.397 270)
			(size 0.9906 2.794)
			(layers "F.Cu" "F.Mask" "F.Paste")
			(net "A_HSC_HIGH_EN")
		)
		(pad "2" smd rect
			(at 0 -1.397 270)
			(size 0.9906 2.794)
			(layers "F.Cu" "F.Mask" "F.Paste")
			(net "A_HSC_OCP_SEL")
		)
		(pad "3" smd rect
			(at 1.999996 1.397 270)
			(size 0.9906 2.794)
			(layers "F.Cu" "F.Mask" "F.Paste")
			(net "A_HSC_LOW_EN")
		)
	)
	(footprint ""
		(layer "F.Cu")
		(at 437.7055 -16.891 -90)
		(property "Reference" "R1U62"
			(at 0 0 270)
			(layer "F.SilkS")
			(hide yes)
			(effects
				(font
					(size 1.27 1.27)
				)
			)
		)
		(property "Value" ""
			(at 0 0 270)
			(layer "F.Fab")
			(effects
				(font
					(size 1.27 1.27)
				)
			)
		)
		(duplicate_pad_numbers_are_jumpers no)
		(fp_poly
			(pts
				(xy -0.2794 -0.1016) (xy 0.2794 -0.1016) (xy 0.2794 0.9906) (xy -0.2794 0.9906)
			)
			(stroke
				(width 0)
				(type default)
			)
			(fill no)
			(layer "F.CrtYd")
		)
		(fp_line
			(start -0.2794 0.9906)
			(end 0.2794 0.9906)
			(stroke
				(width 0.1)
				(type default)
			)
			(layer "F.Fab")
		)
		(fp_line
			(start 0.2794 0.9906)
			(end 0.2794 -0.1016)
			(stroke
				(width 0.1)
				(type default)
			)
			(layer "F.Fab")
		)
		(fp_line
			(start -0.2794 -0.1016)
			(end -0.2794 0.9906)
			(stroke
				(width 0.1)
				(type default)
			)
			(layer "F.Fab")
		)
		(fp_line
			(start 0.2794 -0.1016)
			(end -0.2794 -0.1016)
			(stroke
				(width 0.1)
				(type default)
			)
			(layer "F.Fab")
		)
		(pad "1" smd rect
			(at 0 0 270)
			(size 0.508 0.508)
			(layers "F.Cu" "F.Mask" "F.Paste")
			(net "H_CPU1_MEMKLM_MEMHOT_G_N")
		)
		(pad "2" smd rect
			(at 0 0.889 270)
			(size 0.508 0.508)
			(layers "F.Cu" "F.Mask" "F.Paste")
			(net "H_CPU1_MEMKLM_MEMHOT_G_PCH_N")
		)
		(zone
			(layer "F.Cu")
			(hatch none 0.5)
			(connect_pads
				(clearance 0)
			)
			(min_thickness 0.25)
			(keepout
				(tracks not_allowed)
				(vias allowed)
				(pads allowed)
				(copperpour not_allowed)
				(footprints allowed)
			)
			(placement
				(enabled no)
				(sheetname "")
			)
			(fill
				(thermal_gap 0.5)
				(thermal_bridge_width 0.5)
				(island_removal_mode 0)
			)
			(polygon
				(pts
					(xy 437.0705 -17.145) (xy 437.0705 -16.637) (xy 437.4515 -16.637) (xy 437.4515 -17.145)
				)
			)
		)
		(zone
			(layer "F.Cu")
			(hatch none 0.5)
			(connect_pads
				(clearance 0)
			)
			(min_thickness 0.25)
			(keepout
				(tracks allowed)
				(vias not_allowed)
				(pads allowed)
				(copperpour not_allowed)
				(footprints allowed)
			)
			(placement
				(enabled no)
				(sheetname "")
			)
			(fill
				(thermal_gap 0.5)
				(thermal_bridge_width 0.5)
				(island_removal_mode 0)
			)
			(polygon
				(pts
					(xy 437.4515 -17.145) (xy 437.4515 -16.637) (xy 437.0705 -16.637) (xy 437.0705 -17.145)
				)
			)
		)
	)
	(footprint ""
		(layer "F.Cu")
		(at 155.583636 -120.080786 90)
		(property "Reference" "R3B1"
			(at 0 0 90)
			(layer "F.SilkS")
			(hide yes)
			(effects
				(font
					(size 1.27 1.27)
				)
			)
		)
		(property "Value" ""
			(at 0 0 90)
			(layer "F.Fab")
			(effects
				(font
					(size 1.27 1.27)
				)
			)
		)
		(duplicate_pad_numbers_are_jumpers no)
		(fp_poly
			(pts
				(xy -0.2794 -0.1016) (xy 0.2794 -0.1016) (xy 0.2794 0.9906) (xy -0.2794 0.9906)
			)
			(stroke
				(width 0)
				(type default)
			)
			(fill no)
			(layer "F.CrtYd")
		)
		(fp_line
			(start 0.2794 -0.1016)
			(end -0.2794 -0.1016)
			(stroke
				(width 0.1)
				(type default)
			)
			(layer "F.Fab")
		)
		(fp_line
			(start -0.2794 -0.1016)
			(end -0.2794 0.9906)
			(stroke
				(width 0.1)
				(type default)
			)
			(layer "F.Fab")
		)
		(fp_line
			(start 0.2794 0.9906)
			(end 0.2794 -0.1016)
			(stroke
				(width 0.1)
				(type default)
			)
			(layer "F.Fab")
		)
		(fp_line
			(start -0.2794 0.9906)
			(end 0.2794 0.9906)
			(stroke
				(width 0.1)
				(type default)
			)
			(layer "F.Fab")
		)
		(pad "1" smd rect
			(at 0 0 90)
			(size 0.508 0.508)
			(layers "F.Cu" "F.Mask" "F.Paste")
			(net "SVID_ALERT0_CPU1_N")
		)
		(pad "2" smd rect
			(at 0 0.889 90)
			(size 0.508 0.508)
			(layers "F.Cu" "F.Mask" "F.Paste")
			(net "SVID_ALERT0_CPU1_R_N")
		)
		(zone
			(layer "F.Cu")
			(hatch none 0.5)
			(connect_pads
				(clearance 0)
			)
			(min_thickness 0.25)
			(keepout
				(tracks allowed)
				(vias not_allowed)
				(pads allowed)
				(copperpour not_allowed)
				(footprints allowed)
			)
			(placement
				(enabled no)
				(sheetname "")
			)
			(fill
				(thermal_gap 0.5)
				(thermal_bridge_width 0.5)
				(island_removal_mode 0)
			)
			(polygon
				(pts
					(xy 155.837636 -119.826786) (xy 155.837636 -120.334786) (xy 156.218636 -120.334786) (xy 156.218636 -119.826786)
				)
			)
		)
		(zone
			(layer "F.Cu")
			(hatch none 0.5)
			(connect_pads
				(clearance 0)
			)
			(min_thickness 0.25)
			(keepout
				(tracks not_allowed)
				(vias allowed)
				(pads allowed)
				(copperpour not_allowed)
				(footprints allowed)
			)
			(placement
				(enabled no)
				(sheetname "")
			)
			(fill
				(thermal_gap 0.5)
				(thermal_bridge_width 0.5)
				(island_removal_mode 0)
			)
			(polygon
				(pts
					(xy 156.218636 -119.826786) (xy 156.218636 -120.334786) (xy 155.837636 -120.334786) (xy 155.837636 -119.826786)
				)
			)
		)
	)
	(footprint ""
		(layer "F.Cu")
		(at 8.787638 -7.129018)
		(property "Reference" "CT29"
			(at -0.8382 -0.67818 0)
			(unlocked yes)
			(layer "F.SilkS")
			(effects
				(font
					(size 0.4064 0.254)
					(thickness 0.1524)
				)
				(justify left)
			)
		)
		(property "Value" ""
			(at 0 0 0)
			(layer "F.Fab")
			(effects
				(font
					(size 1.27 1.27)
				)
			)
		)
		(duplicate_pad_numbers_are_jumpers no)
		(fp_poly
			(pts
				(xy 0.3048 -0.1016) (xy 0.3048 0.9906) (xy -0.3048 0.9906) (xy -0.3048 -0.1016)
			)
			(stroke
				(width 0)
				(type default)
			)
			(fill no)
			(layer "F.CrtYd")
		)
		(fp_line
			(start -0.3048 -0.1016)
			(end -0.3048 0.9906)
			(stroke
				(width 0.1)
				(type default)
			)
			(layer "F.Fab")
		)
		(fp_line
			(start -0.3048 0.9906)
			(end 0.3048 0.9906)
			(stroke
				(width 0.1)
				(type default)
			)
			(layer "F.Fab")
		)
		(fp_line
			(start 0.3048 -0.1016)
			(end -0.3048 -0.1016)
			(stroke
				(width 0.1)
				(type default)
			)
			(layer "F.Fab")
		)
		(fp_line
			(start 0.3048 0.9906)
			(end 0.3048 -0.1016)
			(stroke
				(width 0.1)
				(type default)
			)
			(layer "F.Fab")
		)
		(pad "1" smd rect
			(at 0 0)
			(size 0.508 0.508)
			(layers "F.Cu" "F.Mask" "F.Paste")
			(net "VR_PVDDQ_GHJ_PH1_SW")
		)
		(pad "2" smd rect
			(at 0 0.889)
			(size 0.508 0.508)
			(layers "F.Cu" "F.Mask" "F.Paste")
			(net "VR_PVDDQ_GHJ_PH1_SW_RC")
		)
		(zone
			(layer "F.Cu")
			(hatch none 0.5)
			(connect_pads
				(clearance 0)
			)
			(min_thickness 0.25)
			(keepout
				(tracks allowed)
				(vias not_allowed)
				(pads allowed)
				(copperpour not_allowed)
				(footprints allowed)
			)
			(placement
				(enabled no)
				(sheetname "")
			)
			(fill
				(thermal_gap 0.5)
				(thermal_bridge_width 0.5)
				(island_removal_mode 0)
			)
			(polygon
				(pts
					(xy 8.533638 -6.875018) (xy 9.041638 -6.875018) (xy 9.041638 -6.494018) (xy 8.533638 -6.494018)
				)
			)
		)
		(zone
			(layer "F.Cu")
			(hatch none 0.5)
			(connect_pads
				(clearance 0)
			)
			(min_thickness 0.25)
			(keepout
				(tracks not_allowed)
				(vias allowed)
				(pads allowed)
				(copperpour not_allowed)
				(footprints allowed)
			)
			(placement
				(enabled no)
				(sheetname "")
			)
			(fill
				(thermal_gap 0.5)
				(thermal_bridge_width 0.5)
				(island_removal_mode 0)
			)
			(polygon
				(pts
					(xy 8.533638 -6.494018) (xy 9.041638 -6.494018) (xy 9.041638 -6.875018) (xy 8.533638 -6.875018)
				)
			)
		)
	)
	(footprint ""
		(layer "F.Cu")
		(at 417.0045 -64.135 90)
		(property "Reference" "R8E1"
			(at 0 0 90)
			(layer "F.SilkS")
			(hide yes)
			(effects
				(font
					(size 1.27 1.27)
				)
			)
		)
		(property "Value" ""
			(at 0 0 90)
			(layer "F.Fab")
			(effects
				(font
					(size 1.27 1.27)
				)
			)
		)
		(duplicate_pad_numbers_are_jumpers no)
		(fp_poly
			(pts
				(xy -0.2794 -0.1016) (xy 0.2794 -0.1016) (xy 0.2794 0.9906) (xy -0.2794 0.9906)
			)
			(stroke
				(width 0)
				(type default)
			)
			(fill no)
			(layer "F.CrtYd")
		)
		(fp_line
			(start 0.2794 -0.1016)
			(end -0.2794 -0.1016)
			(stroke
				(width 0.1)
				(type default)
			)
			(layer "F.Fab")
		)
		(fp_line
			(start -0.2794 -0.1016)
			(end -0.2794 0.9906)
			(stroke
				(width 0.1)
				(type default)
			)
			(layer "F.Fab")
		)
		(fp_line
			(start 0.2794 0.9906)
			(end 0.2794 -0.1016)
			(stroke
				(width 0.1)
				(type default)
			)
			(layer "F.Fab")
		)
		(fp_line
			(start -0.2794 0.9906)
			(end 0.2794 0.9906)
			(stroke
				(width 0.1)
				(type default)
			)
			(layer "F.Fab")
		)
		(pad "1" smd rect
			(at 0 0 90)
			(size 0.508 0.508)
			(layers "F.Cu" "F.Mask" "F.Paste")
			(net "IRQ_SPI_TPM_N_R")
		)
		(pad "2" smd rect
			(at 0 0.889 90)
			(size 0.508 0.508)
			(layers "F.Cu" "F.Mask" "F.Paste")
			(net "IRQ_PIRQA_SPI_TPM_N")
		)
		(zone
			(layer "F.Cu")
			(hatch none 0.5)
			(connect_pads
				(clearance 0)
			)
			(min_thickness 0.25)
			(keepout
				(tracks allowed)
				(vias not_allowed)
				(pads allowed)
				(copperpour not_allowed)
				(footprints allowed)
			)
			(placement
				(enabled no)
				(sheetname "")
			)
			(fill
				(thermal_gap 0.5)
				(thermal_bridge_width 0.5)
				(island_removal_mode 0)
			)
			(polygon
				(pts
					(xy 417.2585 -63.881) (xy 417.2585 -64.389) (xy 417.6395 -64.389) (xy 417.6395 -63.881)
				)
			)
		)
		(zone
			(layer "F.Cu")
			(hatch none 0.5)
			(connect_pads
				(clearance 0)
			)
			(min_thickness 0.25)
			(keepout
				(tracks not_allowed)
				(vias allowed)
				(pads allowed)
				(copperpour not_allowed)
				(footprints allowed)
			)
			(placement
				(enabled no)
				(sheetname "")
			)
			(fill
				(thermal_gap 0.5)
				(thermal_bridge_width 0.5)
				(island_removal_mode 0)
			)
			(polygon
				(pts
					(xy 417.6395 -63.881) (xy 417.6395 -64.389) (xy 417.2585 -64.389) (xy 417.2585 -63.881)
				)
			)
		)
	)
	(footprint ""
		(layer "F.Cu")
		(at 490.524546 -152.91816 90)
		(property "Reference" "R9A8"
			(at 0 0 90)
			(layer "F.SilkS")
			(hide yes)
			(effects
				(font
					(size 1.27 1.27)
				)
			)
		)
		(property "Value" ""
			(at 0 0 90)
			(layer "F.Fab")
			(effects
				(font
					(size 1.27 1.27)
				)
			)
		)
		(duplicate_pad_numbers_are_jumpers no)
		(fp_poly
			(pts
				(xy -0.2794 -0.1016) (xy 0.2794 -0.1016) (xy 0.2794 0.9906) (xy -0.2794 0.9906)
			)
			(stroke
				(width 0)
				(type default)
			)
			(fill no)
			(layer "F.CrtYd")
		)
		(fp_line
			(start 0.2794 -0.1016)
			(end -0.2794 -0.1016)
			(stroke
				(width 0.1)
				(type default)
			)
			(layer "F.Fab")
		)
		(fp_line
			(start -0.2794 -0.1016)
			(end -0.2794 0.9906)
			(stroke
				(width 0.1)
				(type default)
			)
			(layer "F.Fab")
		)
		(fp_line
			(start 0.2794 0.9906)
			(end 0.2794 -0.1016)
			(stroke
				(width 0.1)
				(type default)
			)
			(layer "F.Fab")
		)
		(fp_line
			(start -0.2794 0.9906)
			(end 0.2794 0.9906)
			(stroke
				(width 0.1)
				(type default)
			)
			(layer "F.Fab")
		)
		(pad "1" smd rect
			(at 0 0 90)
			(size 0.508 0.508)
			(layers "F.Cu" "F.Mask" "F.Paste")
			(net "SPA_SIN_SW_R")
		)
		(pad "2" smd rect
			(at 0 0.889 90)
			(size 0.508 0.508)
			(layers "F.Cu" "F.Mask" "F.Paste")
			(net "SPA_MID_DBG1_RX")
		)
		(zone
			(layer "F.Cu")
			(hatch none 0.5)
			(connect_pads
				(clearance 0)
			)
			(min_thickness 0.25)
			(keepout
				(tracks allowed)
				(vias not_allowed)
				(pads allowed)
				(copperpour not_allowed)
				(footprints allowed)
			)
			(placement
				(enabled no)
				(sheetname "")
			)
			(fill
				(thermal_gap 0.5)
				(thermal_bridge_width 0.5)
				(island_removal_mode 0)
			)
			(polygon
				(pts
					(xy 490.778546 -152.66416) (xy 490.778546 -153.17216) (xy 491.159546 -153.17216) (xy 491.159546 -152.66416)
				)
			)
		)
		(zone
			(layer "F.Cu")
			(hatch none 0.5)
			(connect_pads
				(clearance 0)
			)
			(min_thickness 0.25)
			(keepout
				(tracks not_allowed)
				(vias allowed)
				(pads allowed)
				(copperpour not_allowed)
				(footprints allowed)
			)
			(placement
				(enabled no)
				(sheetname "")
			)
			(fill
				(thermal_gap 0.5)
				(thermal_bridge_width 0.5)
				(island_removal_mode 0)
			)
			(polygon
				(pts
					(xy 491.159546 -152.66416) (xy 491.159546 -153.17216) (xy 490.778546 -153.17216) (xy 490.778546 -152.66416)
				)
			)
		)
	)
)
